#ISCELL
  mstr_misc dns *
  *
#ISCELL
  pure_quanta quanta_title_block_c *
  *
#ISCELL
  standard offpage *
  page187_i1
#ISCELL
  standard offpage *
  page187_i10
#CELL
  pure_quanta q_res *
  page187_i11
#CELL
  pure_quanta q_res *
  page187_i12
#ISCELL
  pure_quanta_power vcc_core *
  page187_i13
#ISCELL
  pure_quanta_power universal_gnd *
  page187_i14
#CELL
  pure_quanta q_cap *
  page187_i15
#ISCELL
  pure_quanta_power universal_gnd *
  page187_i16
#CELL
  pure_quanta q_res *
  page187_i17
#ISCELL
  pure_quanta_power universal_gnd *
  page187_i18
#CELL
  pure_quanta q_res *
  page187_i19
#CELL
  pure_quanta q_cap *
  page187_i2
#CELL
  pure_quanta q_cap *
  page187_i20
#CELL
  pure_quanta q_res *
  page187_i21
#CELL
  pure_quanta q_cap *
  page187_i22
#CELL
  pure_quanta q_cap *
  page187_i23
#CELL
  pure_quanta q_cap *
  page187_i24
#CELL
  pure_quanta q_cap *
  page187_i25
#ISCELL
  pure_quanta_power universal_gnd *
  page187_i26
#CELL
  pure_quanta q_res *
  page187_i27
#CELL
  pure_quanta q_cap *
  page187_i28
#ISCELL
  pure_quanta_power universal_gnd *
  page187_i29
#ISCELL
  pure_quanta_power universal_gnd *
  page187_i3
#ISCELL
  standard offpage *
  page187_i30
#ISCELL
  pure_quanta_power universal_gnd *
  page187_i31
#ISCELL
  standard offpage *
  page187_i32
#ISCELL
  standard offpage *
  page187_i33
#CELL
  pure_quanta q_res *
  page187_i34
#ISCELL
  pure_quanta_power universal_gnd *
  page187_i35
#ISCELL
  standard offpage *
  page187_i36
#CELL
  pure_quanta q_cap *
  page187_i37
#CELL
  pure_quanta q_res *
  page187_i38
#CELL
  pure_quanta isl99390frztr5935 *
  page187_i39
#ISCELL
  pure_quanta_power universal_gnd *
  page187_i4
#ISCELL
  pure_quanta_power universal_gnd *
  page187_i40
#CELL
  pure_quanta q_cap *
  page187_i41
#ISCELL
  pure_quanta_power vcc_core *
  page187_i42
#ISCELL
  pure_quanta_power universal_gnd *
  page187_i43
#CELL
  pure_quanta q_cap *
  page187_i44
#CELL
  pure_quanta q_res *
  page187_i45
#CELL
  pure_quanta q_cap *
  page187_i46
#CELL
  pure_quanta q_res *
  page187_i47
#CELL
  pure_quanta q_cap *
  page187_i48
#CELL
  pure_quanta q_cap *
  page187_i49
#ISCELL
  pure_quanta_power universal_gnd *
  page187_i5
#CELL
  pure_quanta q_cap *
  page187_i50
#ISCELL
  standard offpage *
  page187_i51
#CELL
  pure_quanta q_cap *
  page187_i52
#CELL
  pure_quanta q_inductor4p_14 *
  page187_i53
#ISCELL
  pure_quanta_power universal_gnd *
  page187_i54
#CELL
  pure_quanta q_cap *
  page187_i55
#ISCELL
  pure_quanta_power vcc_core *
  page187_i56
#ISCELL
  pure_quanta_power universal_gnd *
  page187_i57
#CELL
  pure_quanta q_cap *
  page187_i58
#ISCELL
  pure_quanta_power universal_gnd *
  page187_i59
#CELL
  pure_quanta q_cap *
  page187_i6
#CELL
  pure_quanta q_cap *
  page187_i60
#ISCELL
  pure_quanta_power vcc_core *
  page187_i61
#ISCELL
  standard offpage *
  page187_i62
#CELL
  pure_quanta q_cap *
  page187_i63
#ISCELL
  pure_quanta_power universal_gnd *
  page187_i64
#CELL
  pure_quanta q_cap *
  page187_i65
#ISCELL
  pure_quanta_power vcc_core *
  page187_i66
#CELL
  pure_quanta q_inductor4p_14 *
  page187_i67
#ISCELL
  standard offpage *
  page187_i68
#CELL
  pure_quanta q_cap *
  page187_i69
#ISCELL
  standard offpage *
  page187_i7
#ISCELL
  pure_quanta_power universal_gnd *
  page187_i70
#CELL
  pure_quanta q_cap *
  page187_i71
#ISCELL
  pure_quanta_power vcc_core *
  page187_i72
#ISCELL
  standard offpage *
  page187_i8
#CELL
  pure_quanta isl99390frztr5935 *
  page187_i9
